(kicad_pcb
	(version 20260206)
	(generator "pcbnew")
	(generator_version "10.0")
	(general
		(thickness 1.6)
		(legacy_teardrops no)
	)
	(paper "A4")
	(title_block
		(title "01162023_DA0F0TEBIF0_F0T_Expander_BD_F_brd_V02_OCP.brd")
		(comment 1 "Grand Teton / footprints 8990-8998 of 9728")
	)
	(layers
		(0 "F.Cu" signal "TOP")
		(4 "In1.Cu" signal "GND")
		(6 "In2.Cu" signal "VCC")
		(8 "In3.Cu" signal "VCC1")
		(10 "In4.Cu" signal "GND1")
		(12 "In5.Cu" signal "IN1")
		(14 "In6.Cu" signal "GND2")
		(16 "In7.Cu" signal "IN2")
		(18 "In8.Cu" signal "GND3")
		(20 "In9.Cu" signal "IN3")
		(22 "In10.Cu" signal "GND4")
		(24 "In11.Cu" signal "IN4")
		(26 "In12.Cu" signal "GND5")
		(28 "In13.Cu" signal "IN5")
		(30 "In14.Cu" signal "GND6")
		(32 "In15.Cu" signal "IN6")
		(34 "In16.Cu" signal "GND7")
		(2 "B.Cu" signal "BOTTOM")
		(9 "F.Adhes" user "F.Adhesive")
		(11 "B.Adhes" user "B.Adhesive")
		(13 "F.Paste" user "Package Geometry/Pastemask Top")
		(15 "B.Paste" user "Package Geometry/Pastemask Bottom")
		(5 "F.SilkS" user "Ref Des/Silkscreen Top")
		(7 "B.SilkS" user "Ref Des/Silkscreen Bottom")
		(1 "F.Mask" user "Board Geometry/Soldermask Top")
		(3 "B.Mask" user "Board Geometry/Soldermask Bottom")
		(17 "Dwgs.User" user "User.Drawings")
		(19 "Cmts.User" user "User.Comments")
		(21 "Eco1.User" user "User.Eco1")
		(23 "Eco2.User" user "User.Eco2")
		(25 "Edge.Cuts" user "Board Geometry/Outline")
		(27 "Margin" user)
		(31 "F.CrtYd" user "Package Geometry/Place Bound Top")
		(29 "B.CrtYd" user "Package Geometry/Place Bound Bottom")
		(35 "F.Fab" user "Ref Des/Assembly Top")
		(33 "B.Fab" user "Ref Des/Assembly Bottom")
	)
	(footprint ""
		(layer "B.Cu")
		(at 401.774914 -293.99992 -90)
		(property "Reference" "C1916"
			(at 0 0 90)
			(layer "B.SilkS")
			(hide yes)
			(effects
				(font
					(size 1.27 1.27)
				)
				(justify mirror)
			)
		)
		(property "Value" ""
			(at 0 0 90)
			(layer "B.Fab")
			(effects
				(font
					(size 1.27 1.27)
				)
				(justify mirror)
			)
		)
		(duplicate_pad_numbers_are_jumpers no)
		(fp_line
			(start -0.299974 0.150114)
			(end 0.299974 0.150114)
			(stroke
				(width 0.1)
				(type default)
			)
			(layer "B.Fab")
		)
		(fp_line
			(start 0.299974 0.150114)
			(end 0.299974 -0.150114)
			(stroke
				(width 0.1)
				(type default)
			)
			(layer "B.Fab")
		)
		(fp_line
			(start -0.299974 -0.150114)
			(end -0.299974 0.150114)
			(stroke
				(width 0.1)
				(type default)
			)
			(layer "B.Fab")
		)
		(fp_line
			(start 0.299974 -0.150114)
			(end -0.299974 -0.150114)
			(stroke
				(width 0.1)
				(type default)
			)
			(layer "B.Fab")
		)
		(pad "1" smd rect
			(at 0.2667 0 90)
			(size 0.3048 0.381)
			(layers "B.Cu" "B.Mask" "B.Paste")
			(net "P0V8_PEX3")
		)
		(pad "2" smd rect
			(at -0.2667 0 90)
			(size 0.3048 0.381)
			(layers "B.Cu" "B.Mask" "B.Paste")
			(net "GND")
		)
	)
	(footprint ""
		(layer "B.Cu")
		(at 394.65504 -297.32478)
		(property "Reference" "C3550"
			(at 0 0 0)
			(layer "B.SilkS")
			(hide yes)
			(effects
				(font
					(size 1.27 1.27)
				)
				(justify mirror)
			)
		)
		(property "Value" ""
			(at 0 0 0)
			(layer "B.Fab")
			(effects
				(font
					(size 1.27 1.27)
				)
				(justify mirror)
			)
		)
		(duplicate_pad_numbers_are_jumpers no)
		(fp_line
			(start -0.299974 -0.150114)
			(end -0.299974 0.150114)
			(stroke
				(width 0.1)
				(type default)
			)
			(layer "B.Fab")
		)
		(fp_line
			(start -0.299974 0.150114)
			(end 0.299974 0.150114)
			(stroke
				(width 0.1)
				(type default)
			)
			(layer "B.Fab")
		)
		(fp_line
			(start 0.299974 -0.150114)
			(end -0.299974 -0.150114)
			(stroke
				(width 0.1)
				(type default)
			)
			(layer "B.Fab")
		)
		(fp_line
			(start 0.299974 0.150114)
			(end 0.299974 -0.150114)
			(stroke
				(width 0.1)
				(type default)
			)
			(layer "B.Fab")
		)
		(pad "1" smd rect
			(at 0.2667 0 180)
			(size 0.3048 0.381)
			(layers "B.Cu" "B.Mask" "B.Paste")
			(net "PCEPLL2_VDDA18_PEX3")
		)
		(pad "2" smd rect
			(at -0.2667 0 180)
			(size 0.3048 0.381)
			(layers "B.Cu" "B.Mask" "B.Paste")
			(net "GND")
		)
	)
	(footprint ""
		(layer "B.Cu")
		(at 182.87492 -297.79976 -90)
		(property "Reference" "C1447"
			(at 0 0 90)
			(layer "B.SilkS")
			(hide yes)
			(effects
				(font
					(size 1.27 1.27)
				)
				(justify mirror)
			)
		)
		(property "Value" ""
			(at 0 0 90)
			(layer "B.Fab")
			(effects
				(font
					(size 1.27 1.27)
				)
				(justify mirror)
			)
		)
		(duplicate_pad_numbers_are_jumpers no)
		(fp_line
			(start -0.299974 0.150114)
			(end 0.299974 0.150114)
			(stroke
				(width 0.1)
				(type default)
			)
			(layer "B.Fab")
		)
		(fp_line
			(start 0.299974 0.150114)
			(end 0.299974 -0.150114)
			(stroke
				(width 0.1)
				(type default)
			)
			(layer "B.Fab")
		)
		(fp_line
			(start -0.299974 -0.150114)
			(end -0.299974 0.150114)
			(stroke
				(width 0.1)
				(type default)
			)
			(layer "B.Fab")
		)
		(fp_line
			(start 0.299974 -0.150114)
			(end -0.299974 -0.150114)
			(stroke
				(width 0.1)
				(type default)
			)
			(layer "B.Fab")
		)
		(pad "1" smd rect
			(at 0.2667 0 90)
			(size 0.3048 0.381)
			(layers "B.Cu" "B.Mask" "B.Paste")
			(net "P0V8_SERDES_VDDA_PEX1")
		)
		(pad "2" smd rect
			(at -0.2667 0 90)
			(size 0.3048 0.381)
			(layers "B.Cu" "B.Mask" "B.Paste")
			(net "GND")
		)
	)
	(footprint ""
		(layer "B.Cu")
		(at 286.624776 -293.99992 90)
		(property "Reference" "C1657"
			(at 0 0 90)
			(layer "B.SilkS")
			(hide yes)
			(effects
				(font
					(size 1.27 1.27)
				)
				(justify mirror)
			)
		)
		(property "Value" ""
			(at 0 0 90)
			(layer "B.Fab")
			(effects
				(font
					(size 1.27 1.27)
				)
				(justify mirror)
			)
		)
		(duplicate_pad_numbers_are_jumpers no)
		(fp_line
			(start 0.299974 -0.150114)
			(end -0.299974 -0.150114)
			(stroke
				(width 0.1)
				(type default)
			)
			(layer "B.Fab")
		)
		(fp_line
			(start -0.299974 -0.150114)
			(end -0.299974 0.150114)
			(stroke
				(width 0.1)
				(type default)
			)
			(layer "B.Fab")
		)
		(fp_line
			(start 0.299974 0.150114)
			(end 0.299974 -0.150114)
			(stroke
				(width 0.1)
				(type default)
			)
			(layer "B.Fab")
		)
		(fp_line
			(start -0.299974 0.150114)
			(end 0.299974 0.150114)
			(stroke
				(width 0.1)
				(type default)
			)
			(layer "B.Fab")
		)
		(pad "1" smd rect
			(at 0.2667 0 270)
			(size 0.3048 0.381)
			(layers "B.Cu" "B.Mask" "B.Paste")
			(net "P0V8_PEX2")
		)
		(pad "2" smd rect
			(at -0.2667 0 270)
			(size 0.3048 0.381)
			(layers "B.Cu" "B.Mask" "B.Paste")
			(net "GND")
		)
	)
	(footprint ""
		(layer "B.Cu")
		(at 285.199836 -290.199826 90)
		(property "Reference" "C1698"
			(at 0 0 90)
			(layer "B.SilkS")
			(hide yes)
			(effects
				(font
					(size 1.27 1.27)
				)
				(justify mirror)
			)
		)
		(property "Value" ""
			(at 0 0 90)
			(layer "B.Fab")
			(effects
				(font
					(size 1.27 1.27)
				)
				(justify mirror)
			)
		)
		(duplicate_pad_numbers_are_jumpers no)
		(fp_line
			(start 0.299974 -0.150114)
			(end -0.299974 -0.150114)
			(stroke
				(width 0.1)
				(type default)
			)
			(layer "B.Fab")
		)
		(fp_line
			(start -0.299974 -0.150114)
			(end -0.299974 0.150114)
			(stroke
				(width 0.1)
				(type default)
			)
			(layer "B.Fab")
		)
		(fp_line
			(start 0.299974 0.150114)
			(end 0.299974 -0.150114)
			(stroke
				(width 0.1)
				(type default)
			)
			(layer "B.Fab")
		)
		(fp_line
			(start -0.299974 0.150114)
			(end 0.299974 0.150114)
			(stroke
				(width 0.1)
				(type default)
			)
			(layer "B.Fab")
		)
		(pad "1" smd rect
			(at 0.2667 0 270)
			(size 0.3048 0.381)
			(layers "B.Cu" "B.Mask" "B.Paste")
			(net "P0V8_SERDES_VDDA_PEX2")
		)
		(pad "2" smd rect
			(at -0.2667 0 270)
			(size 0.3048 0.381)
			(layers "B.Cu" "B.Mask" "B.Paste")
			(net "GND")
		)
	)
	(footprint ""
		(layer "B.Cu")
		(at 337.970876 -326.945498 -90)
		(property "Reference" "C4329"
			(at 0 0 90)
			(layer "B.SilkS")
			(hide yes)
			(effects
				(font
					(size 1.27 1.27)
				)
				(justify mirror)
			)
		)
		(property "Value" ""
			(at 0 0 90)
			(layer "B.Fab")
			(effects
				(font
					(size 1.27 1.27)
				)
				(justify mirror)
			)
		)
		(duplicate_pad_numbers_are_jumpers no)
		(fp_line
			(start -1.2954 0.5842)
			(end 1.2954 0.5842)
			(stroke
				(width 0.1524)
				(type default)
			)
			(layer "B.SilkS")
		)
		(fp_line
			(start 1.2954 0.5842)
			(end 1.2954 -0.5842)
			(stroke
				(width 0.1524)
				(type default)
			)
			(layer "B.SilkS")
		)
		(fp_line
			(start -1.2954 -0.5842)
			(end -1.2954 0.5842)
			(stroke
				(width 0.1524)
				(type default)
			)
			(layer "B.SilkS")
		)
		(fp_line
			(start 1.2954 -0.5842)
			(end -1.2954 -0.5842)
			(stroke
				(width 0.1524)
				(type default)
			)
			(layer "B.SilkS")
		)
		(fp_line
			(start -0.8636 0.4572)
			(end 0.8636 0.4572)
			(stroke
				(width 0.1)
				(type default)
			)
			(layer "B.Fab")
		)
		(fp_line
			(start 0.8636 0.4572)
			(end 0.8636 0.4064)
			(stroke
				(width 0.1)
				(type default)
			)
			(layer "B.Fab")
		)
		(fp_line
			(start -1.1938 0.4064)
			(end -0.8636 0.4064)
			(stroke
				(width 0.1)
				(type default)
			)
			(layer "B.Fab")
		)
		(fp_line
			(start -0.8636 0.4064)
			(end -0.8636 0.4572)
			(stroke
				(width 0.1)
				(type default)
			)
			(layer "B.Fab")
		)
		(fp_line
			(start 0.8636 0.4064)
			(end 1.1938 0.4064)
			(stroke
				(width 0.1)
				(type default)
			)
			(layer "B.Fab")
		)
		(fp_line
			(start 1.1938 0.4064)
			(end 1.1938 -0.4064)
			(stroke
				(width 0.1)
				(type default)
			)
			(layer "B.Fab")
		)
		(fp_line
			(start -1.1938 -0.4064)
			(end -1.1938 0.4064)
			(stroke
				(width 0.1)
				(type default)
			)
			(layer "B.Fab")
		)
		(fp_line
			(start -0.8636 -0.4064)
			(end -1.1938 -0.4064)
			(stroke
				(width 0.1)
				(type default)
			)
			(layer "B.Fab")
		)
		(fp_line
			(start 0.8636 -0.4064)
			(end 0.8636 -0.4572)
			(stroke
				(width 0.1)
				(type default)
			)
			(layer "B.Fab")
		)
		(fp_line
			(start 1.1938 -0.4064)
			(end 0.8636 -0.4064)
			(stroke
				(width 0.1)
				(type default)
			)
			(layer "B.Fab")
		)
		(fp_line
			(start -0.8636 -0.4572)
			(end -0.8636 -0.4064)
			(stroke
				(width 0.1)
				(type default)
			)
			(layer "B.Fab")
		)
		(fp_line
			(start 0.8636 -0.4572)
			(end -0.8636 -0.4572)
			(stroke
				(width 0.1)
				(type default)
			)
			(layer "B.Fab")
		)
		(pad "1" smd rect
			(at 0.7366 0 180)
			(size 0.7112 0.8128)
			(layers "B.Cu" "B.Mask" "B.Paste")
			(net "P0V8_SERDES_VDDA_PEX2_C11")
		)
		(pad "2" smd rect
			(at -0.7366 0 180)
			(size 0.7112 0.8128)
			(layers "B.Cu" "B.Mask" "B.Paste")
			(net "GND")
		)
	)
	(footprint ""
		(layer "B.Cu")
		(at 182.39994 -299.699934 -90)
		(property "Reference" "C1423"
			(at 0 0 90)
			(layer "B.SilkS")
			(hide yes)
			(effects
				(font
					(size 1.27 1.27)
				)
				(justify mirror)
			)
		)
		(property "Value" ""
			(at 0 0 90)
			(layer "B.Fab")
			(effects
				(font
					(size 1.27 1.27)
				)
				(justify mirror)
			)
		)
		(duplicate_pad_numbers_are_jumpers no)
		(fp_line
			(start -0.299974 0.150114)
			(end 0.299974 0.150114)
			(stroke
				(width 0.1)
				(type default)
			)
			(layer "B.Fab")
		)
		(fp_line
			(start 0.299974 0.150114)
			(end 0.299974 -0.150114)
			(stroke
				(width 0.1)
				(type default)
			)
			(layer "B.Fab")
		)
		(fp_line
			(start -0.299974 -0.150114)
			(end -0.299974 0.150114)
			(stroke
				(width 0.1)
				(type default)
			)
			(layer "B.Fab")
		)
		(fp_line
			(start 0.299974 -0.150114)
			(end -0.299974 -0.150114)
			(stroke
				(width 0.1)
				(type default)
			)
			(layer "B.Fab")
		)
		(pad "1" smd rect
			(at 0.2667 0 90)
			(size 0.3048 0.381)
			(layers "B.Cu" "B.Mask" "B.Paste")
			(net "P0V8_SERDES_VDDA_PEX1")
		)
		(pad "2" smd rect
			(at -0.2667 0 90)
			(size 0.3048 0.381)
			(layers "B.Cu" "B.Mask" "B.Paste")
			(net "GND")
		)
	)
	(footprint ""
		(layer "B.Cu")
		(at 213.730332 -224.398586 180)
		(property "Reference" "R4113"
			(at 0 0 0)
			(layer "B.SilkS")
			(hide yes)
			(effects
				(font
					(size 1.27 1.27)
				)
				(justify mirror)
			)
		)
		(property "Value" ""
			(at 0 0 0)
			(layer "B.Fab")
			(effects
				(font
					(size 1.27 1.27)
				)
				(justify mirror)
			)
		)
		(duplicate_pad_numbers_are_jumpers no)
		(fp_line
			(start 0.7874 0.4064)
			(end 0.7874 -0.4064)
			(stroke
				(width 0.1524)
				(type default)
			)
			(layer "B.SilkS")
		)
		(fp_line
			(start 0.7874 -0.4064)
			(end -0.7874 -0.4064)
			(stroke
				(width 0.1524)
				(type default)
			)
			(layer "B.SilkS")
		)
		(fp_line
			(start -0.7874 0.4064)
			(end 0.7874 0.4064)
			(stroke
				(width 0.1524)
				(type default)
			)
			(layer "B.SilkS")
		)
		(fp_line
			(start -0.7874 -0.4064)
			(end -0.7874 0.4064)
			(stroke
				(width 0.1524)
				(type default)
			)
			(layer "B.SilkS")
		)
		(fp_line
			(start 0.67945 0.3048)
			(end 0.67945 -0.305054)
			(stroke
				(width 0.1)
				(type default)
			)
			(layer "B.Fab")
		)
		(fp_line
			(start 0.67945 -0.305054)
			(end 0.12065 -0.305054)
			(stroke
				(width 0.1)
				(type default)
			)
			(layer "B.Fab")
		)
		(fp_line
			(start 0.12065 0.3048)
			(end 0.67945 0.3048)
			(stroke
				(width 0.1)
				(type default)
			)
			(layer "B.Fab")
		)
		(fp_line
			(start 0.12065 0.2794)
			(end 0.12065 0.3048)
			(stroke
				(width 0.1)
				(type default)
			)
			(layer "B.Fab")
		)
		(fp_line
			(start 0.12065 -0.2794)
			(end -0.12065 -0.2794)
			(stroke
				(width 0.1)
				(type default)
			)
			(layer "B.Fab")
		)
		(fp_line
			(start 0.12065 -0.305054)
			(end 0.12065 -0.2794)
			(stroke
				(width 0.1)
				(type default)
			)
			(layer "B.Fab")
		)
		(fp_line
			(start -0.120396 0.3048)
			(end -0.120396 0.2794)
			(stroke
				(width 0.1)
				(type default)
			)
			(layer "B.Fab")
		)
		(fp_line
			(start -0.120396 0.2794)
			(end 0.12065 0.2794)
			(stroke
				(width 0.1)
				(type default)
			)
			(layer "B.Fab")
		)
		(fp_line
			(start -0.12065 -0.2794)
			(end -0.12065 -0.3048)
			(stroke
				(width 0.1)
				(type default)
			)
			(layer "B.Fab")
		)
		(fp_line
			(start -0.12065 -0.3048)
			(end -0.67945 -0.3048)
			(stroke
				(width 0.1)
				(type default)
			)
			(layer "B.Fab")
		)
		(fp_line
			(start -0.67945 0.3048)
			(end -0.120396 0.3048)
			(stroke
				(width 0.1)
				(type default)
			)
			(layer "B.Fab")
		)
		(fp_line
			(start -0.67945 -0.3048)
			(end -0.67945 0.3048)
			(stroke
				(width 0.1)
				(type default)
			)
			(layer "B.Fab")
		)
		(pad "1" smd circle
			(at 0.40005 0)
			(size 0 0)
			(layers "B.Cu" "B.Mask" "B.Paste")
			(net "P3V3_AUX")
		)
		(pad "2" smd circle
			(at -0.40005 0)
			(size 0 0)
			(layers "B.Cu" "B.Mask" "B.Paste")
			(net "SMB_BIC_I2C6_SCL")
		)
	)
	(footprint ""
		(layer "B.Cu")
		(at 209.212942 -259.311648 90)
		(property "Reference" "R6347"
			(at 0 0 90)
			(layer "B.SilkS")
			(hide yes)
			(effects
				(font
					(size 1.27 1.27)
				)
				(justify mirror)
			)
		)
		(property "Value" ""
			(at 0 0 90)
			(layer "B.Fab")
			(effects
				(font
					(size 1.27 1.27)
				)
				(justify mirror)
			)
		)
		(duplicate_pad_numbers_are_jumpers no)
		(fp_line
			(start 0.7874 -0.4064)
			(end -0.7874 -0.4064)
			(stroke
				(width 0.1524)
				(type default)
			)
			(layer "B.SilkS")
		)
		(fp_line
			(start -0.7874 -0.4064)
			(end -0.7874 0.4064)
			(stroke
				(width 0.1524)
				(type default)
			)
			(layer "B.SilkS")
		)
		(fp_line
			(start 0.7874 0.4064)
			(end 0.7874 -0.4064)
			(stroke
				(width 0.1524)
				(type default)
			)
			(layer "B.SilkS")
		)
		(fp_line
			(start -0.7874 0.4064)
			(end 0.7874 0.4064)
			(stroke
				(width 0.1524)
				(type default)
			)
			(layer "B.SilkS")
		)
		(fp_line
			(start 0.67945 -0.305054)
			(end 0.12065 -0.305054)
			(stroke
				(width 0.1)
				(type default)
			)
			(layer "B.Fab")
		)
		(fp_line
			(start 0.12065 -0.305054)
			(end 0.12065 -0.2794)
			(stroke
				(width 0.1)
				(type default)
			)
			(layer "B.Fab")
		)
		(fp_line
			(start -0.12065 -0.3048)
			(end -0.67945 -0.3048)
			(stroke
				(width 0.1)
				(type default)
			)
			(layer "B.Fab")
		)
		(fp_line
			(start -0.67945 -0.3048)
			(end -0.67945 0.3048)
			(stroke
				(width 0.1)
				(type default)
			)
			(layer "B.Fab")
		)
		(fp_line
			(start 0.12065 -0.2794)
			(end -0.12065 -0.2794)
			(stroke
				(width 0.1)
				(type default)
			)
			(layer "B.Fab")
		)
		(fp_line
			(start -0.12065 -0.2794)
			(end -0.12065 -0.3048)
			(stroke
				(width 0.1)
				(type default)
			)
			(layer "B.Fab")
		)
		(fp_line
			(start 0.12065 0.2794)
			(end 0.12065 0.3048)
			(stroke
				(width 0.1)
				(type default)
			)
			(layer "B.Fab")
		)
		(fp_line
			(start -0.120396 0.2794)
			(end 0.12065 0.2794)
			(stroke
				(width 0.1)
				(type default)
			)
			(layer "B.Fab")
		)
		(fp_line
			(start 0.67945 0.3048)
			(end 0.67945 -0.305054)
			(stroke
				(width 0.1)
				(type default)
			)
			(layer "B.Fab")
		)
		(fp_line
			(start 0.12065 0.3048)
			(end 0.67945 0.3048)
			(stroke
				(width 0.1)
				(type default)
			)
			(layer "B.Fab")
		)
		(fp_line
			(start -0.120396 0.3048)
			(end -0.120396 0.2794)
			(stroke
				(width 0.1)
				(type default)
			)
			(layer "B.Fab")
		)
		(fp_line
			(start -0.67945 0.3048)
			(end -0.120396 0.3048)
			(stroke
				(width 0.1)
				(type default)
			)
			(layer "B.Fab")
		)
		(pad "1" smd circle
			(at 0.40005 0 270)
			(size 0 0)
			(layers "B.Cu" "B.Mask" "B.Paste")
			(net "P1V8_PEX")
		)
		(pad "2" smd circle
			(at -0.40005 0 270)
			(size 0 0)
			(layers "B.Cu" "B.Mask" "B.Paste")
			(net "SMB_PEX2_MUX_SCL")
		)
	)
)
